G04*
G04 #@! TF.GenerationSoftware,Altium Limited,Altium Designer,23.0.1 (38)*
G04*
G04 Layer_Color=32768*
%FSLAX25Y25*%
%MOIN*%
G70*
G04*
G04 #@! TF.SameCoordinates,C48E81DB-6E20-4E2D-80E6-7C5AFAA1A21F*
G04*
G04*
G04 #@! TF.FilePolarity,Positive*
G04*
G01*
G75*
%ADD16C,0.00394*%
D16*
X683858Y-27559D02*
X687795D01*
X685827Y-29528D02*
Y-25591D01*
X563386Y-244882D02*
X567323D01*
X565354Y-246850D02*
Y-242913D01*
X611024Y-275984D02*
X614961D01*
X612992Y-277953D02*
Y-274016D01*
X684252Y-322441D02*
X688189D01*
X686221Y-324409D02*
Y-320472D01*
X670866Y-323228D02*
X674803D01*
X672835Y-325197D02*
Y-321260D01*
X670866Y-315748D02*
X674803D01*
X672835Y-317717D02*
Y-313779D01*
X684252Y-315748D02*
X688189D01*
X686221Y-317717D02*
Y-313779D01*
X691732Y-88976D02*
X695669D01*
X693701Y-90945D02*
Y-87008D01*
X683465Y-53150D02*
X687402D01*
X685433Y-55118D02*
Y-51181D01*
X670472Y-103937D02*
X674409D01*
X672441Y-105905D02*
Y-101969D01*
X664173Y-112598D02*
Y-108661D01*
X662205Y-110630D02*
X666142D01*
X664173Y-112598D02*
Y-108661D01*
X662205Y-110630D02*
X666142D01*
X693701Y-68110D02*
Y-64173D01*
X691732Y-66142D02*
X695669D01*
X669685Y-96457D02*
Y-92520D01*
X667717Y-94488D02*
X671654D01*
X677559Y-31890D02*
X681496D01*
X679528Y-33858D02*
Y-29921D01*
X684646Y-37795D02*
X688583D01*
X686614Y-39764D02*
Y-35827D01*
X692126Y-37931D02*
X696063D01*
X694095Y-39900D02*
Y-35963D01*
X617126Y-95276D02*
Y-91339D01*
X615158Y-93307D02*
X619095D01*
X627559Y-95276D02*
Y-91339D01*
X625591Y-93307D02*
X629528D01*
X584252Y-95276D02*
Y-91339D01*
X582283Y-93307D02*
X586221D01*
X595276Y-92126D02*
X599213D01*
X597244Y-94095D02*
Y-90158D01*
X423622Y-126772D02*
Y-122835D01*
X421654Y-124803D02*
X425591D01*
X407874Y-129921D02*
X411811D01*
X409842Y-131890D02*
Y-127953D01*
X434646Y-129528D02*
X438583D01*
X436614Y-131496D02*
Y-127559D01*
X246457Y-121260D02*
X250394D01*
X248425Y-123228D02*
Y-119291D01*
Y-110630D02*
X252362D01*
X250394Y-112598D02*
Y-108661D01*
X407762Y-117787D02*
X411699D01*
X409730Y-119755D02*
Y-115818D01*
X434646Y-118889D02*
X438583D01*
X436614Y-120858D02*
Y-116921D01*
X548032Y-279921D02*
X551968D01*
X550000Y-281890D02*
Y-277953D01*
X616535Y-217717D02*
Y-213779D01*
X614567Y-215748D02*
X618504D01*
X658268Y-183465D02*
X662205D01*
X660236Y-185433D02*
Y-181496D01*
X681393Y-185180D02*
X685330D01*
X683362Y-187148D02*
Y-183211D01*
X630709Y-235827D02*
Y-231890D01*
X628740Y-233858D02*
X632677D01*
X648425Y-224803D02*
X652362D01*
X650394Y-226772D02*
Y-222835D01*
X561417Y-223622D02*
Y-219685D01*
X559449Y-221654D02*
X563386D01*
X591339Y-239370D02*
Y-235433D01*
X589370Y-237402D02*
X593307D01*
X591339Y-239370D02*
Y-235433D01*
X589370Y-237402D02*
X593307D01*
X597244Y-239764D02*
X601181D01*
X599213Y-241732D02*
Y-237795D01*
X616929Y-235433D02*
Y-231496D01*
X614961Y-233465D02*
X618898D01*
X679921Y-207222D02*
X683858D01*
X681890Y-209191D02*
Y-205254D01*
X673622Y-184646D02*
X677559D01*
X675591Y-186614D02*
Y-182677D01*
X664961Y-207480D02*
X668898D01*
X666929Y-209449D02*
Y-205512D01*
X669291Y-230315D02*
Y-226378D01*
X667323Y-228346D02*
X671260D01*
X617323Y-193307D02*
Y-189370D01*
X615354Y-191339D02*
X619291D01*
X594095Y-188583D02*
X598032D01*
X596063Y-190551D02*
Y-186614D01*
X672441Y-207480D02*
X676378D01*
X674409Y-209449D02*
Y-205512D01*
X584646Y-188583D02*
X588583D01*
X586614Y-190551D02*
Y-186614D01*
X558268Y-199606D02*
X562205D01*
X560236Y-201575D02*
Y-197638D01*
X551575Y-223228D02*
X555512D01*
X553543Y-225197D02*
Y-221260D01*
X560630Y-214567D02*
X564567D01*
X562598Y-216535D02*
Y-212598D01*
X596063Y-136221D02*
Y-132283D01*
X594095Y-134252D02*
X598032D01*
X673401Y-137663D02*
Y-133726D01*
X671432Y-135695D02*
X675369D01*
X564961Y-171260D02*
Y-167323D01*
X562992Y-169291D02*
X566929D01*
X619685Y-298031D02*
Y-294094D01*
X617717Y-296063D02*
X621654D01*
X600394Y-297638D02*
Y-293701D01*
X598425Y-295669D02*
X602362D01*
X559974Y-294488D02*
Y-290551D01*
X558006Y-292520D02*
X561943D01*
X550000Y-293701D02*
Y-289764D01*
X548032Y-291732D02*
X551968D01*
X589764Y-291339D02*
X593701D01*
X591732Y-293307D02*
Y-289370D01*
X589764Y-291339D02*
X593701D01*
X591732Y-293307D02*
Y-289370D01*
X545866Y-259646D02*
X549803D01*
X547835Y-261614D02*
Y-257677D01*
X572441Y-293701D02*
Y-289764D01*
X570472Y-291732D02*
X574409D01*
X592520Y-253543D02*
X596457D01*
X594488Y-255512D02*
Y-251575D01*
X603543Y-253937D02*
X607480D01*
X605512Y-255906D02*
Y-251969D01*
X664173Y-270472D02*
Y-266535D01*
X662205Y-268504D02*
X666142D01*
X641732Y-279921D02*
Y-275984D01*
X639764Y-277953D02*
X643701D01*
X664567Y-278346D02*
Y-274410D01*
X662598Y-276378D02*
X666535D01*
X665380Y-254271D02*
Y-250334D01*
X663412Y-252303D02*
X667348D01*
X665354Y-262205D02*
Y-258268D01*
X663386Y-260236D02*
X667323D01*
X643307Y-256299D02*
Y-252362D01*
X641339Y-254331D02*
X645276D01*
X661417Y-301969D02*
Y-298031D01*
X659449Y-300000D02*
X663386D01*
X641339Y-294882D02*
X645276D01*
X643307Y-296850D02*
Y-292913D01*
X549213Y-126378D02*
X553150D01*
X551181Y-128347D02*
Y-124409D01*
X534646Y-135827D02*
Y-131890D01*
X532677Y-133858D02*
X536614D01*
X498819Y-111811D02*
Y-107874D01*
X496850Y-109843D02*
X500787D01*
X486083Y-122441D02*
X491870D01*
X488976Y-125335D02*
Y-119547D01*
X45276Y-39370D02*
X49213D01*
X47244Y-41339D02*
Y-37402D01*
X122441Y-40945D02*
X126378D01*
X124409Y-42913D02*
Y-38976D01*
X667717Y-58661D02*
Y-54724D01*
X665748Y-56693D02*
X669685D01*
X605512Y-55905D02*
Y-51968D01*
X603543Y-53937D02*
X607480D01*
X625197Y-170472D02*
Y-166535D01*
X623228Y-168504D02*
X627165D01*
X38386Y11811D02*
X42323D01*
X40354Y9843D02*
Y13780D01*
X31496Y11811D02*
X35433D01*
X33465Y9843D02*
Y13780D01*
X24606Y11811D02*
X28543D01*
X26575Y9843D02*
Y13780D01*
X45276Y11811D02*
X49213D01*
X47244Y9843D02*
Y13780D01*
X79921Y-112205D02*
Y-108268D01*
X77953Y-110236D02*
X81890D01*
X73819Y-125394D02*
X77756D01*
X75787Y-127362D02*
Y-123425D01*
X669685Y-25591D02*
Y-21654D01*
X667717Y-23622D02*
X671654D01*
X613189Y-23474D02*
Y-19537D01*
X611221Y-21506D02*
X615158D01*
X87598Y-94340D02*
X91535D01*
X89567Y-96309D02*
Y-92372D01*
X121063Y-76033D02*
X125000D01*
X123031Y-78002D02*
Y-74065D01*
X513779Y-124852D02*
X517717D01*
X515748Y-126821D02*
Y-122883D01*
X458661Y-125836D02*
X462598D01*
X460630Y-127805D02*
Y-123868D01*
M02*
